# TIMECARD (Time Appliance Project (Time Card)) — schematic netlist excerpt (pin names and nets, part order shuffled) for the footprints in the layout excerpt that follows; sources: Cadence DE-HDL packaged netlist, KiCad conversion of R4006-B0001-02_R01.brd

R500  RESISTOR  4.7KOHM 1%  pkg SMC_0402R_H016  page 11 : \1\ = SG ; \2\ = ANT3_IN
R53  RESISTOR  30KOHM 0.1%  pkg SMC_0402R_H016  page 28 : \1\ = VIN_XP3R3 ; \2\ = XP3R3V_EN

(kicad_pcb
	(version 20260206)
	(generator "pcbnew")
	(generator_version "10.0")
	(general
		(thickness 1.6)
		(legacy_teardrops no)
	)
	(paper "A4")
	(title_block
		(title "timecard-production-celestica-r4006 — R4006-B0001-02_R01.brd")
		(comment 1 "Time Appliance Project (Time Card) / footprints 714-715 of 1113")
	)
	(layers
		(0 "F.Cu" signal "TOP")
		(4 "In1.Cu" signal "L02_GND1")
		(6 "In2.Cu" signal "L03_SIG1")
		(8 "In3.Cu" signal "L04_GND2")
		(10 "In4.Cu" signal "L05_VCC1")
		(12 "In5.Cu" signal "L06_VCC2")
		(14 "In6.Cu" signal "L07_GND3")
		(16 "In7.Cu" signal "L08_SIG2")
		(18 "In8.Cu" signal "L09_GND4")
		(2 "B.Cu" signal "BOTTOM")
		(9 "F.Adhes" user "F.Adhesive")
		(11 "B.Adhes" user "B.Adhesive")
		(13 "F.Paste" user "Package Geometry/Pastemask Top")
		(15 "B.Paste" user "Package Geometry/Pastemask Bottom")
		(5 "F.SilkS" user "Ref Des/Silkscreen Top")
		(7 "B.SilkS" user "Ref Des/Silkscreen Bottom")
		(1 "F.Mask" user "Board Geometry/Soldermask Top")
		(3 "B.Mask" user "Board Geometry/Soldermask Bottom")
		(17 "Dwgs.User" user "User.Drawings")
		(19 "Cmts.User" user "User.Comments")
		(21 "Eco1.User" user "User.Eco1")
		(23 "Eco2.User" user "User.Eco2")
		(25 "Edge.Cuts" user "Board Geometry/Outline")
		(27 "Margin" user)
		(31 "F.CrtYd" user "Package Geometry/Place Bound Top")
		(29 "B.CrtYd" user "Package Geometry/Place Bound Bottom")
		(35 "F.Fab" user "Ref Des/Assembly Top")
		(33 "B.Fab" user "Ref Des/Assembly Bottom")
	)
	(footprint ""
		(layer "B.Cu")
		(at 89.9922 -103.5558)
		(property "Reference" "R53"
			(at 3.7338 0.09017 0)
			(unlocked yes)
			(layer "B.SilkS")
			(effects
				(font
					(size 0.7874 0.5842)
					(thickness 0.1524)
				)
				(justify mirror)
			)
		)
		(property "Value" "VAL*"
			(at -0.02032 2.13233 0)
			(unlocked yes)
			(layer "B.Fab")
			(hide yes)
			(effects
				(font
					(size 0.7874 0.5842)
					(thickness 0.1524)
				)
				(justify mirror)
			)
		)
		(property "Tolerance" "TOL*"
			(at -0.044704 3.05435 0)
			(unlocked yes)
			(layer "Cmts.User")
			(hide yes)
			(effects
				(font
					(size 0.7874 0.5842)
					(thickness 0.1524)
				)
				(justify mirror)
			)
		)
		(property "User Part Number" "PARTNUM*"
			(at -0.02032 4.024884 0)
			(unlocked yes)
			(layer "Cmts.User")
			(hide yes)
			(effects
				(font
					(size 0.7874 0.5842)
					(thickness 0.1524)
				)
				(justify mirror)
			)
		)
		(property "Device Type" "RESISTOR-G152-10344-01,30KOHM,A"
			(at -0.008382 1.210564 0)
			(unlocked yes)
			(layer "B.Fab")
			(hide yes)
			(effects
				(font
					(size 0.7874 0.5842)
					(thickness 0.1524)
				)
				(justify mirror)
			)
		)
		(duplicate_pad_numbers_are_jumpers no)
		(fp_line
			(start -1.143 -0.5588)
			(end 1.143 -0.5588)
			(stroke
				(width 0.1)
				(type default)
			)
			(layer "B.SilkS")
		)
		(fp_line
			(start -1.143 0.5588)
			(end -1.143 -0.5588)
			(stroke
				(width 0.1)
				(type default)
			)
			(layer "B.SilkS")
		)
		(fp_line
			(start 1.143 -0.5588)
			(end 1.143 0.5588)
			(stroke
				(width 0.1)
				(type default)
			)
			(layer "B.SilkS")
		)
		(fp_line
			(start 1.143 0.5588)
			(end -1.143 0.5588)
			(stroke
				(width 0.1)
				(type default)
			)
			(layer "B.SilkS")
		)
		(fp_rect
			(start -1.143 0.5588)
			(end 1.143 -0.5588)
			(stroke
				(width 0)
				(type default)
			)
			(fill no)
			(layer "B.CrtYd")
		)
		(fp_line
			(start -0.508 -0.3048)
			(end 0.508 -0.3048)
			(stroke
				(width 0.1)
				(type default)
			)
			(layer "B.Fab")
		)
		(fp_line
			(start -0.508 0.3048)
			(end -0.508 -0.3048)
			(stroke
				(width 0.1)
				(type default)
			)
			(layer "B.Fab")
		)
		(fp_line
			(start 0.508 -0.3048)
			(end 0.508 0.3048)
			(stroke
				(width 0.1)
				(type default)
			)
			(layer "B.Fab")
		)
		(fp_line
			(start 0.508 0.3048)
			(end -0.508 0.3048)
			(stroke
				(width 0.1)
				(type default)
			)
			(layer "B.Fab")
		)
		(pad "1" smd rect
			(at 0.5334 0 180)
			(size 0.7112 0.6096)
			(layers "B.Cu" "B.Mask" "B.Paste")
			(net "VIN_XP3R3")
		)
		(pad "2" smd rect
			(at -0.5334 0 180)
			(size 0.7112 0.6096)
			(layers "B.Cu" "B.Mask" "B.Paste")
			(net "XP3R3V_EN")
		)
		(zone
			(layer "B.Cu")
			(hatch none 0.5)
			(connect_pads
				(clearance 0)
			)
			(min_thickness 0.25)
			(keepout
				(tracks not_allowed)
				(vias allowed)
				(pads allowed)
				(copperpour not_allowed)
				(footprints allowed)
			)
			(placement
				(enabled no)
				(sheetname "")
			)
			(fill
				(thermal_gap 0.5)
				(thermal_bridge_width 0.5)
				(island_removal_mode 0)
			)
			(polygon
				(pts
					(xy 89.916 -103.251) (xy 90.0684 -103.251) (xy 90.0684 -103.8606) (xy 89.916 -103.8606)
				)
			)
		)
		(zone
			(layer "B.Cu")
			(hatch none 0.5)
			(connect_pads
				(clearance 0)
			)
			(min_thickness 0.25)
			(keepout
				(tracks allowed)
				(vias not_allowed)
				(pads allowed)
				(copperpour not_allowed)
				(footprints allowed)
			)
			(placement
				(enabled no)
				(sheetname "")
			)
			(fill
				(thermal_gap 0.5)
				(thermal_bridge_width 0.5)
				(island_removal_mode 0)
			)
			(polygon
				(pts
					(xy 89.916 -103.251) (xy 90.0684 -103.251) (xy 90.0684 -103.8606) (xy 89.916 -103.8606)
				)
			)
		)
	)
	(footprint ""
		(layer "B.Cu")
		(at 119.34698 -42.82313)
		(property "Reference" "R500"
			(at 2.79527 0.78613 270)
			(unlocked yes)
			(layer "B.SilkS")
			(effects
				(font
					(size 0.635 0.4064)
					(thickness 0.1524)
				)
				(justify mirror)
			)
		)
		(property "Value" "VAL*"
			(at 0 3.718306 0)
			(unlocked yes)
			(layer "B.Fab")
			(hide yes)
			(effects
				(font
					(size 0.7874 0.5842)
					(thickness 0.127)
				)
				(justify mirror)
			)
		)
		(property "Tolerance" "TOL*"
			(at 0 4.861306 0)
			(unlocked yes)
			(layer "Cmts.User")
			(hide yes)
			(effects
				(font
					(size 0.7874 0.5842)
					(thickness 0.127)
				)
				(justify mirror)
			)
		)
		(property "User Part Number" "PARTNUM*"
			(at 0 2.575306 0)
			(unlocked yes)
			(layer "Cmts.User")
			(hide yes)
			(effects
				(font
					(size 0.7874 0.5842)
					(thickness 0.127)
				)
				(justify mirror)
			)
		)
		(property "Device Type" "RESISTOR-G155-14701-01,4.7KOHMA"
			(at 0 1.432306 0)
			(unlocked yes)
			(layer "B.Fab")
			(hide yes)
			(effects
				(font
					(size 0.7874 0.5842)
					(thickness 0.127)
				)
				(justify mirror)
			)
		)
		(duplicate_pad_numbers_are_jumpers no)
		(fp_line
			(start -0.970026 -0.4699)
			(end -0.970026 0.4699)
			(stroke
				(width 0.1)
				(type default)
			)
			(layer "B.SilkS")
		)
		(fp_line
			(start -0.970026 0.4699)
			(end 0.970026 0.4699)
			(stroke
				(width 0.1)
				(type default)
			)
			(layer "B.SilkS")
		)
		(fp_line
			(start 0.970026 -0.4699)
			(end -0.970026 -0.4699)
			(stroke
				(width 0.1)
				(type default)
			)
			(layer "B.SilkS")
		)
		(fp_line
			(start 0.970026 0.4699)
			(end 0.970026 -0.4699)
			(stroke
				(width 0.1)
				(type default)
			)
			(layer "B.SilkS")
		)
		(fp_poly
			(pts
				(xy 0.970026 0.4699) (xy -0.970026 0.4699) (xy -0.970026 -0.4699) (xy 0.970026 -0.4699)
			)
			(stroke
				(width 0)
				(type default)
			)
			(fill no)
			(layer "B.CrtYd")
		)
		(fp_line
			(start -0.508 -0.3048)
			(end -0.508 0.3048)
			(stroke
				(width 0.1)
				(type default)
			)
			(layer "B.Fab")
		)
		(fp_line
			(start -0.508 0.3048)
			(end 0.508 0.3048)
			(stroke
				(width 0.1)
				(type default)
			)
			(layer "B.Fab")
		)
		(fp_line
			(start 0.508 -0.3048)
			(end -0.508 -0.3048)
			(stroke
				(width 0.1)
				(type default)
			)
			(layer "B.Fab")
		)
		(fp_line
			(start 0.508 0.3048)
			(end 0.508 -0.3048)
			(stroke
				(width 0.1)
				(type default)
			)
			(layer "B.Fab")
		)
		(pad "1" smd circle
			(at 0.500126 0 180)
			(size 0.635 0.635)
			(layers "B.Cu" "B.Mask" "B.Paste")
			(net "SG")
		)
		(pad "2" smd circle
			(at -0.500126 0 180)
			(size 0.635 0.635)
			(layers "B.Cu" "B.Mask" "B.Paste")
			(net "ANT3_IN")
		)
	)
)
